(kicad_pcb
	(version 20260206)
	(generator "pcbnew")
	(generator_version "10.0")
	(general
		(thickness 1.6)
		(legacy_teardrops no)
	)
	(paper "A4")
	(title_block
		(title "Bryce Canyon_R.DPB_16317-1_OCP.brd")
		(comment 1 "Bryce Canyon / footprints 1354-1360 of 2099")
	)
	(layers
		(0 "F.Cu" signal "TOP")
		(4 "In1.Cu" signal "L2GND")
		(6 "In2.Cu" signal "L3")
		(8 "In3.Cu" signal "L4VCC")
		(10 "In4.Cu" signal "L5VCC")
		(12 "In5.Cu" signal "L6")
		(14 "In6.Cu" signal "L7GND")
		(2 "B.Cu" signal "BOTTOM")
		(9 "F.Adhes" user "F.Adhesive")
		(11 "B.Adhes" user "B.Adhesive")
		(13 "F.Paste" user "Package Geometry/Pastemask Top")
		(15 "B.Paste" user "Package Geometry/Pastemask Bottom")
		(5 "F.SilkS" user "Ref Des/Silkscreen Top")
		(7 "B.SilkS" user "Ref Des/Silkscreen Bottom")
		(1 "F.Mask" user "Board Geometry/Soldermask Top")
		(3 "B.Mask" user "Board Geometry/Soldermask Bottom")
		(17 "Dwgs.User" user "User.Drawings")
		(19 "Cmts.User" user "User.Comments")
		(21 "Eco1.User" user "User.Eco1")
		(23 "Eco2.User" user "User.Eco2")
		(25 "Edge.Cuts" user "Board Geometry/Outline")
		(27 "Margin" user)
		(31 "F.CrtYd" user "Package Geometry/Place Bound Top")
		(29 "B.CrtYd" user "Package Geometry/Place Bound Bottom")
		(35 "F.Fab" user "Ref Des/Assembly Top")
		(33 "B.Fab" user "Ref Des/Assembly Bottom")
	)
	(footprint ""
		(layer "F.Cu")
		(at 45.814996 -358.3559)
		(property "Reference" "R147"
			(at 0 0 0)
			(layer "F.SilkS")
			(hide yes)
			(effects
				(font
					(size 1.27 1.27)
				)
			)
		)
		(property "Value" "200KR2F-L-GP"
			(at 0.064008 -3.993896 0)
			(unlocked yes)
			(layer "F.Fab")
			(hide yes)
			(effects
				(font
					(size 1.016 1.016)
					(thickness 0.1524)
				)
			)
		)
		(property "Device Type" "R402H16"
			(at 0.064008 -5.517896 0)
			(unlocked yes)
			(layer "F.Fab")
			(hide yes)
			(effects
				(font
					(size 1.016 1.016)
					(thickness 0.1524)
				)
			)
		)
		(duplicate_pad_numbers_are_jumpers no)
		(fp_line
			(start -0.508 -0.9398)
			(end -0.508 0.9398)
			(stroke
				(width 0.1524)
				(type default)
			)
			(layer "F.SilkS")
		)
		(fp_line
			(start 0.508 -0.9398)
			(end -0.508 -0.9398)
			(stroke
				(width 0.1524)
				(type default)
			)
			(layer "F.SilkS")
		)
		(fp_rect
			(start -0.508 0.9398)
			(end 0.508 -0.9398)
			(stroke
				(width 0)
				(type default)
			)
			(fill no)
			(layer "F.CrtYd")
		)
		(fp_rect
			(start -0.508 0.9398)
			(end 0.508 -0.9398)
			(stroke
				(width 0)
				(type default)
			)
			(fill no)
			(layer "F.Fab")
		)
		(pad "1" smd custom
			(at 0 -0.4445)
			(size 0.1397 0.1397)
			(layers "F.Cu" "F.Mask" "F.Paste")
			(net "GATE_FAN0")
			(options
				(clearance outline)
				(anchor circle)
			)
			(primitives
				(gr_poly
					(pts
						(arc
							(start -0.1778 -0.2794)
							(mid -0.249642 -0.249642)
							(end -0.2794 -0.1778)
						)
						(arc
							(start -0.2794 0.1778)
							(mid -0.249642 0.249642)
							(end -0.1778 0.2794)
						)
						(arc
							(start 0.1778 0.2794)
							(mid 0.249642 0.249642)
							(end 0.2794 0.1778)
						)
						(arc
							(start 0.2794 -0.1778)
							(mid 0.249642 -0.249642)
							(end 0.1778 -0.2794)
						)
					)
					(width 0)
					(fill yes)
				)
			)
		)
		(pad "2" smd custom
			(at 0 0.4445)
			(size 0.1397 0.1397)
			(layers "F.Cu" "F.Mask" "F.Paste")
			(net "GATE_FAN0_R")
			(options
				(clearance outline)
				(anchor circle)
			)
			(primitives
				(gr_poly
					(pts
						(arc
							(start -0.1778 -0.2794)
							(mid -0.249642 -0.249642)
							(end -0.2794 -0.1778)
						)
						(arc
							(start -0.2794 0.1778)
							(mid -0.249642 0.249642)
							(end -0.1778 0.2794)
						)
						(arc
							(start 0.1778 0.2794)
							(mid 0.249642 0.249642)
							(end 0.2794 0.1778)
						)
						(arc
							(start 0.2794 -0.1778)
							(mid 0.249642 -0.249642)
							(end 0.1778 -0.2794)
						)
					)
					(width 0)
					(fill yes)
				)
			)
		)
	)
	(footprint ""
		(layer "F.Cu")
		(at 383.8956 -261.6454 180)
		(property "Reference" "R287"
			(at 0 0 180)
			(layer "F.SilkS")
			(hide yes)
			(effects
				(font
					(size 1.27 1.27)
				)
			)
		)
		(property "Value" "10KR2F-2-GP"
			(at 0.064008 -3.993896 180)
			(unlocked yes)
			(layer "F.Fab")
			(hide yes)
			(effects
				(font
					(size 1.016 1.016)
					(thickness 0.1524)
				)
			)
		)
		(property "Device Type" "R402H16"
			(at 0.064008 -5.517896 180)
			(unlocked yes)
			(layer "F.Fab")
			(hide yes)
			(effects
				(font
					(size 1.016 1.016)
					(thickness 0.1524)
				)
			)
		)
		(duplicate_pad_numbers_are_jumpers no)
		(fp_line
			(start 0.508 -0.9398)
			(end -0.508 -0.9398)
			(stroke
				(width 0.1524)
				(type default)
			)
			(layer "F.SilkS")
		)
		(fp_line
			(start -0.508 -0.9398)
			(end -0.508 0.9398)
			(stroke
				(width 0.1524)
				(type default)
			)
			(layer "F.SilkS")
		)
		(fp_rect
			(start -0.508 0.9398)
			(end 0.508 -0.9398)
			(stroke
				(width 0)
				(type default)
			)
			(fill no)
			(layer "F.CrtYd")
		)
		(fp_rect
			(start -0.508 0.9398)
			(end 0.508 -0.9398)
			(stroke
				(width 0)
				(type default)
			)
			(fill no)
			(layer "F.Fab")
		)
		(pad "1" smd custom
			(at 0 -0.4445 180)
			(size 0.1397 0.1397)
			(layers "F.Cu" "F.Mask" "F.Paste")
			(net "P3V3_STBY_B")
			(options
				(clearance outline)
				(anchor circle)
			)
			(primitives
				(gr_poly
					(pts
						(arc
							(start -0.1778 -0.2794)
							(mid -0.249642 -0.249642)
							(end -0.2794 -0.1778)
						)
						(arc
							(start -0.2794 0.1778)
							(mid -0.249642 0.249642)
							(end -0.1778 0.2794)
						)
						(arc
							(start 0.1778 0.2794)
							(mid 0.249642 0.249642)
							(end 0.2794 0.1778)
						)
						(arc
							(start 0.2794 -0.1778)
							(mid 0.249642 -0.249642)
							(end 0.1778 -0.2794)
						)
					)
					(width 0)
					(fill yes)
				)
			)
		)
		(pad "2" smd custom
			(at 0 0.4445 180)
			(size 0.1397 0.1397)
			(layers "F.Cu" "F.Mask" "F.Paste")
			(net "HDD_PRSNT_8")
			(options
				(clearance outline)
				(anchor circle)
			)
			(primitives
				(gr_poly
					(pts
						(arc
							(start -0.1778 -0.2794)
							(mid -0.249642 -0.249642)
							(end -0.2794 -0.1778)
						)
						(arc
							(start -0.2794 0.1778)
							(mid -0.249642 0.249642)
							(end -0.1778 0.2794)
						)
						(arc
							(start 0.1778 0.2794)
							(mid 0.249642 0.249642)
							(end 0.2794 0.1778)
						)
						(arc
							(start 0.2794 -0.1778)
							(mid 0.249642 -0.249642)
							(end 0.1778 -0.2794)
						)
					)
					(width 0)
					(fill yes)
				)
			)
		)
	)
	(footprint ""
		(layer "F.Cu")
		(at 213.23046 -162.98926 90)
		(property "Reference" "C11"
			(at 0 0 90)
			(layer "F.SilkS")
			(hide yes)
			(effects
				(font
					(size 1.27 1.27)
				)
			)
		)
		(property "Value" "SC1U16V3KX-5GP"
			(at 0 -2.8194 90)
			(unlocked yes)
			(layer "F.Fab")
			(hide yes)
			(effects
				(font
					(size 1.016 1.016)
					(thickness 0.1524)
				)
			)
		)
		(property "Device Type" "C603H36"
			(at 0 -4.3434 90)
			(unlocked yes)
			(layer "F.Fab")
			(hide yes)
			(effects
				(font
					(size 1.016 1.016)
					(thickness 0.1524)
				)
			)
		)
		(duplicate_pad_numbers_are_jumpers no)
		(fp_line
			(start 0.508 0)
			(end -0.508 0)
			(stroke
				(width 0.2032)
				(type default)
			)
			(layer "F.SilkS")
		)
		(fp_rect
			(start -0.5842 1.3335)
			(end 0.5842 -1.3335)
			(stroke
				(width 0)
				(type default)
			)
			(fill no)
			(layer "F.CrtYd")
		)
		(fp_rect
			(start -0.5842 1.3335)
			(end 0.5842 -1.3335)
			(stroke
				(width 0)
				(type default)
			)
			(fill no)
			(layer "F.Fab")
		)
		(pad "1" smd custom
			(at 0 -0.762 90)
			(size 0.2159 0.2159)
			(layers "F.Cu" "F.Mask" "F.Paste")
			(net "P3V3_STBY_B")
			(options
				(clearance outline)
				(anchor circle)
			)
			(primitives
				(gr_poly
					(pts
						(arc
							(start -0.3302 -0.4318)
							(mid -0.402042 -0.402042)
							(end -0.4318 -0.3302)
						)
						(arc
							(start -0.4318 0.3302)
							(mid -0.402042 0.402042)
							(end -0.3302 0.4318)
						)
						(arc
							(start 0.3302 0.4318)
							(mid 0.402042 0.402042)
							(end 0.4318 0.3302)
						)
						(arc
							(start 0.4318 -0.3302)
							(mid 0.402042 -0.402042)
							(end 0.3302 -0.4318)
						)
					)
					(width 0)
					(fill yes)
				)
			)
		)
		(pad "2" smd custom
			(at 0 0.762 90)
			(size 0.2159 0.2159)
			(layers "F.Cu" "F.Mask" "F.Paste")
			(net "GND")
			(options
				(clearance outline)
				(anchor circle)
			)
			(primitives
				(gr_poly
					(pts
						(arc
							(start -0.3302 -0.4318)
							(mid -0.402042 -0.402042)
							(end -0.4318 -0.3302)
						)
						(arc
							(start -0.4318 0.3302)
							(mid -0.402042 0.402042)
							(end -0.3302 0.4318)
						)
						(arc
							(start 0.3302 0.4318)
							(mid 0.402042 0.402042)
							(end 0.4318 0.3302)
						)
						(arc
							(start 0.4318 -0.3302)
							(mid 0.402042 -0.402042)
							(end 0.3302 -0.4318)
						)
					)
					(width 0)
					(fill yes)
				)
			)
		)
	)
	(footprint ""
		(layer "F.Cu")
		(at 323.360796 -378.1044 90)
		(property "Reference" "R1299"
			(at 0 0 90)
			(layer "F.SilkS")
			(hide yes)
			(effects
				(font
					(size 1.27 1.27)
				)
			)
		)
		(property "Value" "4K7R2F-GP"
			(at 0.064008 -3.993896 90)
			(unlocked yes)
			(layer "F.Fab")
			(hide yes)
			(effects
				(font
					(size 1.016 1.016)
					(thickness 0.1524)
				)
			)
		)
		(property "Device Type" "R402H16"
			(at 0.064008 -5.517896 90)
			(unlocked yes)
			(layer "F.Fab")
			(hide yes)
			(effects
				(font
					(size 1.016 1.016)
					(thickness 0.1524)
				)
			)
		)
		(duplicate_pad_numbers_are_jumpers no)
		(fp_line
			(start 0.508 -0.9398)
			(end -0.508 -0.9398)
			(stroke
				(width 0.1524)
				(type default)
			)
			(layer "F.SilkS")
		)
		(fp_line
			(start -0.508 -0.9398)
			(end -0.508 0.9398)
			(stroke
				(width 0.1524)
				(type default)
			)
			(layer "F.SilkS")
		)
		(fp_rect
			(start -0.508 0.9398)
			(end 0.508 -0.9398)
			(stroke
				(width 0)
				(type default)
			)
			(fill no)
			(layer "F.CrtYd")
		)
		(fp_rect
			(start -0.508 0.9398)
			(end 0.508 -0.9398)
			(stroke
				(width 0)
				(type default)
			)
			(fill no)
			(layer "F.Fab")
		)
		(pad "1" smd custom
			(at 0 -0.4445 90)
			(size 0.1397 0.1397)
			(layers "F.Cu" "F.Mask" "F.Paste")
			(net "FAN_YELLOW_LED2")
			(options
				(clearance outline)
				(anchor circle)
			)
			(primitives
				(gr_poly
					(pts
						(arc
							(start -0.1778 -0.2794)
							(mid -0.249642 -0.249642)
							(end -0.2794 -0.1778)
						)
						(arc
							(start -0.2794 0.1778)
							(mid -0.249642 0.249642)
							(end -0.1778 0.2794)
						)
						(arc
							(start 0.1778 0.2794)
							(mid 0.249642 0.249642)
							(end 0.2794 0.1778)
						)
						(arc
							(start 0.2794 -0.1778)
							(mid 0.249642 -0.249642)
							(end 0.1778 -0.2794)
						)
					)
					(width 0)
					(fill yes)
				)
			)
		)
		(pad "2" smd custom
			(at 0 0.4445 90)
			(size 0.1397 0.1397)
			(layers "F.Cu" "F.Mask" "F.Paste")
			(net "P12V_IN")
			(options
				(clearance outline)
				(anchor circle)
			)
			(primitives
				(gr_poly
					(pts
						(arc
							(start -0.1778 -0.2794)
							(mid -0.249642 -0.249642)
							(end -0.2794 -0.1778)
						)
						(arc
							(start -0.2794 0.1778)
							(mid -0.249642 0.249642)
							(end -0.1778 0.2794)
						)
						(arc
							(start 0.1778 0.2794)
							(mid 0.249642 0.249642)
							(end 0.2794 0.1778)
						)
						(arc
							(start 0.2794 -0.1778)
							(mid 0.249642 -0.249642)
							(end 0.1778 -0.2794)
						)
					)
					(width 0)
					(fill yes)
				)
			)
		)
	)
	(footprint ""
		(layer "F.Cu")
		(at 461.584802 -232.16235)
		(property "Reference" "R1135"
			(at 0 0 0)
			(layer "F.SilkS")
			(hide yes)
			(effects
				(font
					(size 1.27 1.27)
				)
			)
		)
		(property "Value" "49K9R2F-L-GP"
			(at 0.064008 -3.993896 0)
			(unlocked yes)
			(layer "F.Fab")
			(hide yes)
			(effects
				(font
					(size 1.016 1.016)
					(thickness 0.1524)
				)
			)
		)
		(property "Device Type" "R402H16"
			(at 0.064008 -5.517896 0)
			(unlocked yes)
			(layer "F.Fab")
			(hide yes)
			(effects
				(font
					(size 1.016 1.016)
					(thickness 0.1524)
				)
			)
		)
		(duplicate_pad_numbers_are_jumpers no)
		(fp_line
			(start -0.508 -0.9398)
			(end -0.508 0.9398)
			(stroke
				(width 0.1524)
				(type default)
			)
			(layer "F.SilkS")
		)
		(fp_line
			(start 0.508 -0.9398)
			(end -0.508 -0.9398)
			(stroke
				(width 0.1524)
				(type default)
			)
			(layer "F.SilkS")
		)
		(fp_rect
			(start -0.508 0.9398)
			(end 0.508 -0.9398)
			(stroke
				(width 0)
				(type default)
			)
			(fill no)
			(layer "F.CrtYd")
		)
		(fp_rect
			(start -0.508 0.9398)
			(end 0.508 -0.9398)
			(stroke
				(width 0)
				(type default)
			)
			(fill no)
			(layer "F.Fab")
		)
		(pad "1" smd custom
			(at 0 -0.4445)
			(size 0.1397 0.1397)
			(layers "F.Cu" "F.Mask" "F.Paste")
			(net "P12V_B")
			(options
				(clearance outline)
				(anchor circle)
			)
			(primitives
				(gr_poly
					(pts
						(arc
							(start -0.1778 -0.2794)
							(mid -0.249642 -0.249642)
							(end -0.2794 -0.1778)
						)
						(arc
							(start -0.2794 0.1778)
							(mid -0.249642 0.249642)
							(end -0.1778 0.2794)
						)
						(arc
							(start 0.1778 0.2794)
							(mid 0.249642 0.249642)
							(end 0.2794 0.1778)
						)
						(arc
							(start 0.2794 -0.1778)
							(mid 0.249642 -0.249642)
							(end 0.1778 -0.2794)
						)
					)
					(width 0)
					(fill yes)
				)
			)
		)
		(pad "2" smd custom
			(at 0 0.4445)
			(size 0.1397 0.1397)
			(layers "F.Cu" "F.Mask" "F.Paste")
			(net "P5V_B_3_EN_R")
			(options
				(clearance outline)
				(anchor circle)
			)
			(primitives
				(gr_poly
					(pts
						(arc
							(start -0.1778 -0.2794)
							(mid -0.249642 -0.249642)
							(end -0.2794 -0.1778)
						)
						(arc
							(start -0.2794 0.1778)
							(mid -0.249642 0.249642)
							(end -0.1778 0.2794)
						)
						(arc
							(start 0.1778 0.2794)
							(mid 0.249642 0.249642)
							(end 0.2794 0.1778)
						)
						(arc
							(start 0.2794 -0.1778)
							(mid 0.249642 -0.249642)
							(end 0.1778 -0.2794)
						)
					)
					(width 0)
					(fill yes)
				)
			)
		)
	)
	(footprint ""
		(layer "F.Cu")
		(at 177.9778 -263.779 -90)
		(property "Reference" "C95"
			(at 0 0 270)
			(layer "F.SilkS")
			(hide yes)
			(effects
				(font
					(size 1.27 1.27)
				)
			)
		)
		(property "Value" "SC1U16V3KX-5GP"
			(at 0 -2.8194 270)
			(unlocked yes)
			(layer "F.Fab")
			(hide yes)
			(effects
				(font
					(size 1.016 1.016)
					(thickness 0.1524)
				)
			)
		)
		(property "Device Type" "C603H36"
			(at 0 -4.3434 270)
			(unlocked yes)
			(layer "F.Fab")
			(hide yes)
			(effects
				(font
					(size 1.016 1.016)
					(thickness 0.1524)
				)
			)
		)
		(duplicate_pad_numbers_are_jumpers no)
		(fp_line
			(start 0.508 0)
			(end -0.508 0)
			(stroke
				(width 0.2032)
				(type default)
			)
			(layer "F.SilkS")
		)
		(fp_rect
			(start -0.5842 1.3335)
			(end 0.5842 -1.3335)
			(stroke
				(width 0)
				(type default)
			)
			(fill no)
			(layer "F.CrtYd")
		)
		(fp_rect
			(start -0.5842 1.3335)
			(end 0.5842 -1.3335)
			(stroke
				(width 0)
				(type default)
			)
			(fill no)
			(layer "F.Fab")
		)
		(pad "1" smd custom
			(at 0 -0.762 270)
			(size 0.2159 0.2159)
			(layers "F.Cu" "F.Mask" "F.Paste")
			(net "P5V_HDD5")
			(options
				(clearance outline)
				(anchor circle)
			)
			(primitives
				(gr_poly
					(pts
						(arc
							(start -0.3302 -0.4318)
							(mid -0.402042 -0.402042)
							(end -0.4318 -0.3302)
						)
						(arc
							(start -0.4318 0.3302)
							(mid -0.402042 0.402042)
							(end -0.3302 0.4318)
						)
						(arc
							(start 0.3302 0.4318)
							(mid 0.402042 0.402042)
							(end 0.4318 0.3302)
						)
						(arc
							(start 0.4318 -0.3302)
							(mid 0.402042 -0.402042)
							(end 0.3302 -0.4318)
						)
					)
					(width 0)
					(fill yes)
				)
			)
		)
		(pad "2" smd custom
			(at 0 0.762 270)
			(size 0.2159 0.2159)
			(layers "F.Cu" "F.Mask" "F.Paste")
			(net "GND")
			(options
				(clearance outline)
				(anchor circle)
			)
			(primitives
				(gr_poly
					(pts
						(arc
							(start -0.3302 -0.4318)
							(mid -0.402042 -0.402042)
							(end -0.4318 -0.3302)
						)
						(arc
							(start -0.4318 0.3302)
							(mid -0.402042 0.402042)
							(end -0.3302 0.4318)
						)
						(arc
							(start 0.3302 0.4318)
							(mid 0.402042 0.402042)
							(end 0.4318 0.3302)
						)
						(arc
							(start 0.4318 -0.3302)
							(mid 0.402042 -0.402042)
							(end 0.3302 -0.4318)
						)
					)
					(width 0)
					(fill yes)
				)
			)
		)
	)
	(footprint ""
		(layer "F.Cu")
		(at 367.284 -13.589 180)
		(property "Reference" "R793"
			(at 0 0 180)
			(layer "F.SilkS")
			(hide yes)
			(effects
				(font
					(size 1.27 1.27)
				)
			)
		)
		(property "Value" "0R2J-2-GP"
			(at 0.064008 -3.993896 180)
			(unlocked yes)
			(layer "F.Fab")
			(hide yes)
			(effects
				(font
					(size 1.016 1.016)
					(thickness 0.1524)
				)
			)
		)
		(property "Device Type" "R402H16"
			(at 0.064008 -5.517896 180)
			(unlocked yes)
			(layer "F.Fab")
			(hide yes)
			(effects
				(font
					(size 1.016 1.016)
					(thickness 0.1524)
				)
			)
		)
		(duplicate_pad_numbers_are_jumpers no)
		(fp_line
			(start 0.508 -0.9398)
			(end -0.508 -0.9398)
			(stroke
				(width 0.1524)
				(type default)
			)
			(layer "F.SilkS")
		)
		(fp_line
			(start -0.508 -0.9398)
			(end -0.508 0.9398)
			(stroke
				(width 0.1524)
				(type default)
			)
			(layer "F.SilkS")
		)
		(fp_rect
			(start -0.508 0.9398)
			(end 0.508 -0.9398)
			(stroke
				(width 0)
				(type default)
			)
			(fill no)
			(layer "F.CrtYd")
		)
		(fp_rect
			(start -0.508 0.9398)
			(end 0.508 -0.9398)
			(stroke
				(width 0)
				(type default)
			)
			(fill no)
			(layer "F.Fab")
		)
		(pad "1" smd custom
			(at 0 -0.4445 180)
			(size 0.1397 0.1397)
			(layers "F.Cu" "F.Mask" "F.Paste")
			(net "DRIVE_B_31_PWR")
			(options
				(clearance outline)
				(anchor circle)
			)
			(primitives
				(gr_poly
					(pts
						(arc
							(start -0.1778 -0.2794)
							(mid -0.249642 -0.249642)
							(end -0.2794 -0.1778)
						)
						(arc
							(start -0.2794 0.1778)
							(mid -0.249642 0.249642)
							(end -0.1778 0.2794)
						)
						(arc
							(start 0.1778 0.2794)
							(mid 0.249642 0.249642)
							(end 0.2794 0.1778)
						)
						(arc
							(start 0.2794 -0.1778)
							(mid 0.249642 -0.249642)
							(end 0.1778 -0.2794)
						)
					)
					(width 0)
					(fill yes)
				)
			)
		)
		(pad "2" smd custom
			(at 0 0.4445 180)
			(size 0.1397 0.1397)
			(layers "F.Cu" "F.Mask" "F.Paste")
			(net "SW_PWR_R_HDD31")
			(options
				(clearance outline)
				(anchor circle)
			)
			(primitives
				(gr_poly
					(pts
						(arc
							(start -0.1778 -0.2794)
							(mid -0.249642 -0.249642)
							(end -0.2794 -0.1778)
						)
						(arc
							(start -0.2794 0.1778)
							(mid -0.249642 0.249642)
							(end -0.1778 0.2794)
						)
						(arc
							(start 0.1778 0.2794)
							(mid 0.249642 0.249642)
							(end 0.2794 0.1778)
						)
						(arc
							(start 0.2794 -0.1778)
							(mid 0.249642 -0.249642)
							(end 0.1778 -0.2794)
						)
					)
					(width 0)
					(fill yes)
				)
			)
		)
	)
)
